# ZAIUS-LBB-EVT2-X01-BOM-X03-20161116.xls — Component Qual Tracker (bom)
|  |  |  |  |  |  |  |  | Part to be included on following build: |  |  |  |  |  |
| Item No. | Part Group | Single/Sole/Multi | Item Description | ODM P/N | Dell PN | Vendor | Vendor P/N | X00 Build | X01 Build | X02 Build | Qual Build | Qualification Target Date | Qualification Complete Date |
|  | VR Controllers |  |  |  |  | Vendor #1 |  |  |  |  |  |  |  |
|  |  |  |  |  |  | Vendor #2 |  |  |  |  |  |  |  |
|  | FETS |  |  |  |  | Vendor #1 |  |  |  |  |  |  |  |
|  |  |  |  |  |  | Vendor #2 |  |  |  |  |  |  |  |
|  | INDUCTORS |  |  |  |  | Vendor #1 |  |  |  |  |  |  |  |
|  |  |  |  |  |  | Vendor #2 |  |  |  |  |  |  |  |
|  | VREG CAPS |  |  |  |  | Vendor #1 |  |  |  |  |  |  |  |
|  |  |  |  |  |  | Vendor #2 |  |  |  |  |  |  |  |
|  | CRYSTALS |  |  |  |  | Vendor #1 |  |  |  |  |  |  |  |
|  |  |  |  |  |  | Vendor #2 |  |  |  |  |  |  |  |
|  | CONNECTORS |  |  |  |  | Vendor #1 |  |  |  |  |  |  |  |
|  |  |  |  |  |  | Vendor #2 |  |  |  |  |  |  |  |
|  | IC'S |  |  |  |  | Vendor #1 |  |  |  |  |  |  |  |
|  |  |  |  |  |  | Vendor #2 |  |  |  |  |  |  |  |
|  | MISC. |  |  |  |  | Vendor #1 |  |  |  |  |  |  |  |
|  | (HEATSINKS) |  |  |  |  | Vendor #2 |  |  |  |  |  |  |  |
